# S9S_MB_2U (Grand Teton) — schematic netlist excerpt (pin names and nets, part order shuffled) for the footprints in the layout excerpt that follows; sources: Cadence DE-HDL packaged netlist, KiCad conversion of 03242023_DA0F0TMBIJ0_F0T_Motherboard_J_brd_V01_OCP.brd

R4050  Q_RES  33.2 1% CHIP  pkg 0402LF  page 225 : A = H_CPU_ERR0_LVC2_R_N ; B = H_CPU_ERR0_LVC2_N
PC579  Q_CAPP  270UF 16V 20% OSCON  pkg THLF  page 285 : A = SW_P12V_PVCCIN_CPU1_FLT ; B = GND
C2337  Q_CAP  0.1UF 25V 10% X7R  pkg 0402  page 237 : A = P3V3_AUX ; B = GND

(kicad_pcb
	(version 20260206)
	(generator "pcbnew")
	(generator_version "10.0")
	(general
		(thickness 1.6)
		(legacy_teardrops no)
	)
	(paper "A4")
	(title_block
		(title "03242023_DA0F0TMBIJ0_F0T_Motherboard_J_brd_V01_OCP.brd")
		(comment 1 "Grand Teton / footprints 2312-2314 of 6105")
	)
	(layers
		(0 "F.Cu" signal "TOP")
		(4 "In1.Cu" signal "GND")
		(6 "In2.Cu" signal "IN1")
		(8 "In3.Cu" signal "GND1")
		(10 "In4.Cu" signal "IN2")
		(12 "In5.Cu" signal "GND2")
		(14 "In6.Cu" signal "IN3")
		(16 "In7.Cu" signal "GND3")
		(18 "In8.Cu" signal "VCC")
		(20 "In9.Cu" signal "VCC1")
		(22 "In10.Cu" signal "GND4")
		(24 "In11.Cu" signal "IN4")
		(26 "In12.Cu" signal "GND5")
		(28 "In13.Cu" signal "IN5")
		(30 "In14.Cu" signal "GND6")
		(32 "In15.Cu" signal "IN6")
		(34 "In16.Cu" signal "GND7")
		(2 "B.Cu" signal "BOTTOM")
		(9 "F.Adhes" user "F.Adhesive")
		(11 "B.Adhes" user "B.Adhesive")
		(13 "F.Paste" user "Package Geometry/Pastemask Top")
		(15 "B.Paste" user "Package Geometry/Pastemask Bottom")
		(5 "F.SilkS" user "Ref Des/Silkscreen Top")
		(7 "B.SilkS" user "Ref Des/Silkscreen Bottom")
		(1 "F.Mask" user "Board Geometry/Soldermask Top")
		(3 "B.Mask" user "Board Geometry/Soldermask Bottom")
		(17 "Dwgs.User" user "User.Drawings")
		(19 "Cmts.User" user "User.Comments")
		(21 "Eco1.User" user "User.Eco1")
		(23 "Eco2.User" user "User.Eco2")
		(25 "Edge.Cuts" user "Board Geometry/Outline")
		(27 "Margin" user)
		(31 "F.CrtYd" user "Package Geometry/Place Bound Top")
		(29 "B.CrtYd" user "Package Geometry/Place Bound Bottom")
		(35 "F.Fab" user "Ref Des/Assembly Top")
		(33 "B.Fab" user "Ref Des/Assembly Bottom")
	)
	(footprint ""
		(layer "F.Cu")
		(at 139.02182 -92.644468 -90)
		(property "Reference" "R4050"
			(at 0 0 270)
			(layer "F.SilkS")
			(hide yes)
			(effects
				(font
					(size 1.27 1.27)
				)
			)
		)
		(property "Value" ""
			(at 0 0 270)
			(layer "F.Fab")
			(effects
				(font
					(size 1.27 1.27)
				)
			)
		)
		(duplicate_pad_numbers_are_jumpers no)
		(fp_line
			(start -0.7874 0.4064)
			(end -0.7874 -0.4064)
			(stroke
				(width 0.1524)
				(type default)
			)
			(layer "F.SilkS")
		)
		(fp_line
			(start 0.7874 0.4064)
			(end -0.7874 0.4064)
			(stroke
				(width 0.1524)
				(type default)
			)
			(layer "F.SilkS")
		)
		(fp_line
			(start -0.7874 -0.4064)
			(end 0.7874 -0.4064)
			(stroke
				(width 0.1524)
				(type default)
			)
			(layer "F.SilkS")
		)
		(fp_line
			(start 0.7874 -0.4064)
			(end 0.7874 0.4064)
			(stroke
				(width 0.1524)
				(type default)
			)
			(layer "F.SilkS")
		)
		(fp_line
			(start -0.67945 0.3048)
			(end -0.67945 -0.305054)
			(stroke
				(width 0.1)
				(type default)
			)
			(layer "F.Fab")
		)
		(fp_line
			(start -0.12065 0.3048)
			(end -0.67945 0.3048)
			(stroke
				(width 0.1)
				(type default)
			)
			(layer "F.Fab")
		)
		(fp_line
			(start 0.120396 0.3048)
			(end 0.120396 0.2794)
			(stroke
				(width 0.1)
				(type default)
			)
			(layer "F.Fab")
		)
		(fp_line
			(start 0.67945 0.3048)
			(end 0.120396 0.3048)
			(stroke
				(width 0.1)
				(type default)
			)
			(layer "F.Fab")
		)
		(fp_line
			(start -0.12065 0.2794)
			(end -0.12065 0.3048)
			(stroke
				(width 0.1)
				(type default)
			)
			(layer "F.Fab")
		)
		(fp_line
			(start 0.120396 0.2794)
			(end -0.12065 0.2794)
			(stroke
				(width 0.1)
				(type default)
			)
			(layer "F.Fab")
		)
		(fp_line
			(start -0.12065 -0.2794)
			(end 0.12065 -0.2794)
			(stroke
				(width 0.1)
				(type default)
			)
			(layer "F.Fab")
		)
		(fp_line
			(start 0.12065 -0.2794)
			(end 0.12065 -0.3048)
			(stroke
				(width 0.1)
				(type default)
			)
			(layer "F.Fab")
		)
		(fp_line
			(start 0.12065 -0.3048)
			(end 0.67945 -0.3048)
			(stroke
				(width 0.1)
				(type default)
			)
			(layer "F.Fab")
		)
		(fp_line
			(start 0.67945 -0.3048)
			(end 0.67945 0.3048)
			(stroke
				(width 0.1)
				(type default)
			)
			(layer "F.Fab")
		)
		(fp_line
			(start -0.67945 -0.305054)
			(end -0.12065 -0.305054)
			(stroke
				(width 0.1)
				(type default)
			)
			(layer "F.Fab")
		)
		(fp_line
			(start -0.12065 -0.305054)
			(end -0.12065 -0.2794)
			(stroke
				(width 0.1)
				(type default)
			)
			(layer "F.Fab")
		)
		(pad "1" smd circle
			(at -0.40005 0 270)
			(size 0 0)
			(layers "F.Cu" "F.Mask" "F.Paste")
			(net "H_CPU_ERR0_LVC2_R_N")
		)
		(pad "2" smd circle
			(at 0.40005 0 270)
			(size 0 0)
			(layers "F.Cu" "F.Mask" "F.Paste")
			(net "H_CPU_ERR0_LVC2_N")
		)
	)
	(footprint ""
		(layer "F.Cu")
		(at 273.091656 -129.44983)
		(property "Reference" "C2337"
			(at 0 0 0)
			(layer "F.SilkS")
			(hide yes)
			(effects
				(font
					(size 1.27 1.27)
				)
			)
		)
		(property "Value" ""
			(at 0 0 0)
			(layer "F.Fab")
			(effects
				(font
					(size 1.27 1.27)
				)
			)
		)
		(duplicate_pad_numbers_are_jumpers no)
		(fp_line
			(start -0.7874 -0.4064)
			(end 0.7874 -0.4064)
			(stroke
				(width 0.1524)
				(type default)
			)
			(layer "F.SilkS")
		)
		(fp_line
			(start -0.7874 0.4064)
			(end -0.7874 -0.4064)
			(stroke
				(width 0.1524)
				(type default)
			)
			(layer "F.SilkS")
		)
		(fp_line
			(start 0.7874 -0.4064)
			(end 0.7874 0.4064)
			(stroke
				(width 0.1524)
				(type default)
			)
			(layer "F.SilkS")
		)
		(fp_line
			(start 0.7874 0.4064)
			(end -0.7874 0.4064)
			(stroke
				(width 0.1524)
				(type default)
			)
			(layer "F.SilkS")
		)
		(fp_line
			(start -0.67945 -0.305054)
			(end -0.12065 -0.305054)
			(stroke
				(width 0.1)
				(type default)
			)
			(layer "F.Fab")
		)
		(fp_line
			(start -0.67945 0.3048)
			(end -0.67945 -0.305054)
			(stroke
				(width 0.1)
				(type default)
			)
			(layer "F.Fab")
		)
		(fp_line
			(start -0.12065 -0.305054)
			(end -0.12065 -0.2794)
			(stroke
				(width 0.1)
				(type default)
			)
			(layer "F.Fab")
		)
		(fp_line
			(start -0.12065 -0.2794)
			(end 0.12065 -0.2794)
			(stroke
				(width 0.1)
				(type default)
			)
			(layer "F.Fab")
		)
		(fp_line
			(start -0.12065 0.2794)
			(end -0.12065 0.3048)
			(stroke
				(width 0.1)
				(type default)
			)
			(layer "F.Fab")
		)
		(fp_line
			(start -0.12065 0.3048)
			(end -0.67945 0.3048)
			(stroke
				(width 0.1)
				(type default)
			)
			(layer "F.Fab")
		)
		(fp_line
			(start 0.120396 0.2794)
			(end -0.12065 0.2794)
			(stroke
				(width 0.1)
				(type default)
			)
			(layer "F.Fab")
		)
		(fp_line
			(start 0.120396 0.3048)
			(end 0.120396 0.2794)
			(stroke
				(width 0.1)
				(type default)
			)
			(layer "F.Fab")
		)
		(fp_line
			(start 0.12065 -0.3048)
			(end 0.67945 -0.3048)
			(stroke
				(width 0.1)
				(type default)
			)
			(layer "F.Fab")
		)
		(fp_line
			(start 0.12065 -0.2794)
			(end 0.12065 -0.3048)
			(stroke
				(width 0.1)
				(type default)
			)
			(layer "F.Fab")
		)
		(fp_line
			(start 0.67945 -0.3048)
			(end 0.67945 0.3048)
			(stroke
				(width 0.1)
				(type default)
			)
			(layer "F.Fab")
		)
		(fp_line
			(start 0.67945 0.3048)
			(end 0.120396 0.3048)
			(stroke
				(width 0.1)
				(type default)
			)
			(layer "F.Fab")
		)
		(pad "1" smd circle
			(at -0.40005 0)
			(size 0 0)
			(layers "F.Cu" "F.Mask" "F.Paste")
			(net "P3V3_AUX")
		)
		(pad "2" smd circle
			(at 0.40005 0)
			(size 0 0)
			(layers "F.Cu" "F.Mask" "F.Paste")
			(net "GND")
		)
	)
	(footprint ""
		(layer "F.Cu")
		(at 97.338896 -344.029284 90)
		(property "Reference" "PC579"
			(at 0 0 90)
			(layer "F.SilkS")
			(hide yes)
			(effects
				(font
					(size 1.27 1.27)
				)
			)
		)
		(property "Value" ""
			(at 0 0 90)
			(layer "F.Fab")
			(effects
				(font
					(size 1.27 1.27)
				)
			)
		)
		(duplicate_pad_numbers_are_jumpers no)
		(fp_line
			(start -3.400044 1.249934)
			(end 3.400044 1.249934)
			(stroke
				(width 0.1524)
				(type default)
			)
			(layer "F.SilkS")
		)
		(fp_circle
			(center 0 1.249934)
			(end 0 4.649978)
			(stroke
				(width 0.1524)
				(type default)
			)
			(fill no)
			(layer "F.SilkS")
		)
		(fp_poly
			(pts
				(arc
					(start -3.400044 1.249934)
					(mid 0 4.649978)
					(end 3.400044 1.249934)
				)
			)
			(stroke
				(width 0)
				(type default)
			)
			(fill yes)
			(layer "F.SilkS")
		)
		(fp_circle
			(center 0 1.249934)
			(end 0 4.649978)
			(stroke
				(width 0.1)
				(type default)
			)
			(fill no)
			(layer "F.Fab")
		)
		(pad "1" thru_hole rect
			(at 0 0 90)
			(size 1.524 1.524)
			(drill 1.016)
			(layers "*.Cu" "*.Mask")
			(remove_unused_layers no)
			(net "SW_P12V_PVCCIN_CPU1_FLT")
			(clearance 0)
			(padstack
				(mode front_inner_back)
				(layer "Inner"
					(shape circle)
					(size 1.524 1.524)
					(clearance 0)
				)
				(layer "B.Cu"
					(shape rect)
					(size 1.524 1.524)
					(clearance 0)
				)
			)
		)
		(pad "2" thru_hole circle
			(at 0 2.500122 90)
			(size 1.524 1.524)
			(drill 1.016)
			(layers "*.Cu" "*.Mask")
			(remove_unused_layers no)
			(net "GND")
			(clearance 0)
		)
	)
)
